(kicad_pcb
	(version 20260206)
	(generator "pcbnew")
	(generator_version "10.0")
	(general
		(thickness 1.6)
		(legacy_teardrops no)
	)
	(paper "A4")
	(title_block
		(title "03242023_DA0F0TMBIJ0_F0T_Motherboard_J_brd_V01_OCP.brd")
		(comment 1 "Grand Teton / footprint 2194 of 6105 (J15), pads 113-224 of 291")
	)
	(layers
		(0 "F.Cu" signal "TOP")
		(4 "In1.Cu" signal "GND")
		(6 "In2.Cu" signal "IN1")
		(8 "In3.Cu" signal "GND1")
		(10 "In4.Cu" signal "IN2")
		(12 "In5.Cu" signal "GND2")
		(14 "In6.Cu" signal "IN3")
		(16 "In7.Cu" signal "GND3")
		(18 "In8.Cu" signal "VCC")
		(20 "In9.Cu" signal "VCC1")
		(22 "In10.Cu" signal "GND4")
		(24 "In11.Cu" signal "IN4")
		(26 "In12.Cu" signal "GND5")
		(28 "In13.Cu" signal "IN5")
		(30 "In14.Cu" signal "GND6")
		(32 "In15.Cu" signal "IN6")
		(34 "In16.Cu" signal "GND7")
		(2 "B.Cu" signal "BOTTOM")
		(9 "F.Adhes" user "F.Adhesive")
		(11 "B.Adhes" user "B.Adhesive")
		(13 "F.Paste" user "Package Geometry/Pastemask Top")
		(15 "B.Paste" user "Package Geometry/Pastemask Bottom")
		(5 "F.SilkS" user "Ref Des/Silkscreen Top")
		(7 "B.SilkS" user "Ref Des/Silkscreen Bottom")
		(1 "F.Mask" user "Board Geometry/Soldermask Top")
		(3 "B.Mask" user "Board Geometry/Soldermask Bottom")
		(17 "Dwgs.User" user "User.Drawings")
		(19 "Cmts.User" user "User.Comments")
		(21 "Eco1.User" user "User.Eco1")
		(23 "Eco2.User" user "User.Eco2")
		(25 "Edge.Cuts" user "Board Geometry/Outline")
		(27 "Margin" user)
		(31 "F.CrtYd" user "Package Geometry/Place Bound Top")
		(29 "B.CrtYd" user "Package Geometry/Place Bound Bottom")
		(35 "F.Fab" user "Ref Des/Assembly Top")
		(33 "B.Fab" user "Ref Des/Assembly Bottom")
	)
	(footprint ""
		(layer "F.Cu")
		(at 461.609948 -258.091686)
		(property "Reference" "J15"
			(at 3.019552 -81.652872 0)
			(unlocked yes)
			(layer "F.SilkS")
			(effects
				(font
					(size 0.7874 0.5842)
					(thickness 0.1524)
				)
				(justify left)
			)
		)
		(property "Value" ""
			(at 0 0 0)
			(layer "F.Fab")
			(effects
				(font
					(size 1.27 1.27)
				)
			)
		)
		(duplicate_pad_numbers_are_jumpers no)
		(pad "113" smd rect
			(at -2.050034 36.975034 270)
			(size 0.519938 1.4986)
			(layers "F.Cu" "F.Mask" "F.Paste")
			(net "M_H_CPU0_SB_DQ<9>")
		)
		(pad "114" smd rect
			(at -2.050034 37.824918 270)
			(size 0.519938 1.4986)
			(layers "F.Cu" "F.Mask" "F.Paste")
			(net "GND")
		)
		(pad "115" smd rect
			(at -2.050034 38.675056 270)
			(size 0.519938 1.4986)
			(layers "F.Cu" "F.Mask" "F.Paste")
			(net "M_H_CPU0_SB_DQS_DP<1>")
		)
		(pad "116" smd rect
			(at -2.050034 39.52494 270)
			(size 0.519938 1.4986)
			(layers "F.Cu" "F.Mask" "F.Paste")
			(net "M_H_CPU0_SB_DQS_DN<1>")
		)
		(pad "117" smd rect
			(at -2.050034 40.375078 270)
			(size 0.519938 1.4986)
			(layers "F.Cu" "F.Mask" "F.Paste")
			(net "GND")
		)
		(pad "118" smd rect
			(at -2.050034 41.224962 270)
			(size 0.519938 1.4986)
			(layers "F.Cu" "F.Mask" "F.Paste")
			(net "M_H_CPU0_SB_DQ<12>")
		)
		(pad "119" smd rect
			(at -2.050034 42.0751 270)
			(size 0.519938 1.4986)
			(layers "F.Cu" "F.Mask" "F.Paste")
			(net "GND")
		)
		(pad "120" smd rect
			(at -2.050034 42.924984 270)
			(size 0.519938 1.4986)
			(layers "F.Cu" "F.Mask" "F.Paste")
			(net "M_H_CPU0_SB_DQ<13>")
		)
		(pad "121" smd rect
			(at -2.050034 43.775122 270)
			(size 0.519938 1.4986)
			(layers "F.Cu" "F.Mask" "F.Paste")
			(net "GND")
		)
		(pad "122" smd rect
			(at -2.050034 44.625006 270)
			(size 0.519938 1.4986)
			(layers "F.Cu" "F.Mask" "F.Paste")
			(net "M_H_CPU0_SB_DQ<16>")
		)
		(pad "123" smd rect
			(at -2.050034 45.47489 270)
			(size 0.519938 1.4986)
			(layers "F.Cu" "F.Mask" "F.Paste")
			(net "GND")
		)
		(pad "124" smd rect
			(at -2.050034 46.325028 270)
			(size 0.519938 1.4986)
			(layers "F.Cu" "F.Mask" "F.Paste")
			(net "M_H_CPU0_SB_DQ<17>")
		)
		(pad "125" smd rect
			(at -2.050034 47.174912 270)
			(size 0.519938 1.4986)
			(layers "F.Cu" "F.Mask" "F.Paste")
			(net "GND")
		)
		(pad "126" smd rect
			(at -2.050034 48.02505 270)
			(size 0.519938 1.4986)
			(layers "F.Cu" "F.Mask" "F.Paste")
			(net "M_H_CPU0_SB_DQS_DP<2>")
		)
		(pad "127" smd rect
			(at -2.050034 48.874934 270)
			(size 0.519938 1.4986)
			(layers "F.Cu" "F.Mask" "F.Paste")
			(net "M_H_CPU0_SB_DQS_DN<2>")
		)
		(pad "128" smd rect
			(at -2.050034 49.725072 270)
			(size 0.519938 1.4986)
			(layers "F.Cu" "F.Mask" "F.Paste")
			(net "GND")
		)
		(pad "129" smd rect
			(at -2.050034 50.574956 270)
			(size 0.519938 1.4986)
			(layers "F.Cu" "F.Mask" "F.Paste")
			(net "M_H_CPU0_SB_DQ<20>")
		)
		(pad "130" smd rect
			(at -2.050034 51.425094 270)
			(size 0.519938 1.4986)
			(layers "F.Cu" "F.Mask" "F.Paste")
			(net "GND")
		)
		(pad "131" smd rect
			(at -2.050034 52.274978 270)
			(size 0.519938 1.4986)
			(layers "F.Cu" "F.Mask" "F.Paste")
			(net "M_H_CPU0_SB_DQ<21>")
		)
		(pad "132" smd rect
			(at -2.050034 53.125116 270)
			(size 0.519938 1.4986)
			(layers "F.Cu" "F.Mask" "F.Paste")
			(net "GND")
		)
		(pad "133" smd rect
			(at -2.050034 53.975 270)
			(size 0.519938 1.4986)
			(layers "F.Cu" "F.Mask" "F.Paste")
			(net "M_H_CPU0_SB_DQ<24>")
		)
		(pad "134" smd rect
			(at -2.050034 54.824884 270)
			(size 0.519938 1.4986)
			(layers "F.Cu" "F.Mask" "F.Paste")
			(net "GND")
		)
		(pad "135" smd rect
			(at -2.050034 55.675022 270)
			(size 0.519938 1.4986)
			(layers "F.Cu" "F.Mask" "F.Paste")
			(net "M_H_CPU0_SB_DQ<25>")
		)
		(pad "136" smd rect
			(at -2.050034 56.524906 270)
			(size 0.519938 1.4986)
			(layers "F.Cu" "F.Mask" "F.Paste")
			(net "GND")
		)
		(pad "137" smd rect
			(at -2.050034 57.375044 270)
			(size 0.519938 1.4986)
			(layers "F.Cu" "F.Mask" "F.Paste")
			(net "M_H_CPU0_SB_DQS_DP<3>")
		)
		(pad "138" smd rect
			(at -2.050034 58.224928 270)
			(size 0.519938 1.4986)
			(layers "F.Cu" "F.Mask" "F.Paste")
			(net "M_H_CPU0_SB_DQS_DN<3>")
		)
		(pad "139" smd rect
			(at -2.050034 59.075066 270)
			(size 0.519938 1.4986)
			(layers "F.Cu" "F.Mask" "F.Paste")
			(net "GND")
		)
		(pad "140" smd rect
			(at -2.050034 59.92495 270)
			(size 0.519938 1.4986)
			(layers "F.Cu" "F.Mask" "F.Paste")
			(net "M_H_CPU0_SB_DQ<28>")
		)
		(pad "141" smd rect
			(at -2.050034 60.775088 270)
			(size 0.519938 1.4986)
			(layers "F.Cu" "F.Mask" "F.Paste")
			(net "GND")
		)
		(pad "142" smd rect
			(at -2.050034 61.624972 270)
			(size 0.519938 1.4986)
			(layers "F.Cu" "F.Mask" "F.Paste")
			(net "M_H_CPU0_SB_DQ<29>")
		)
		(pad "143" smd rect
			(at -2.050034 62.47511 270)
			(size 0.519938 1.4986)
			(layers "F.Cu" "F.Mask" "F.Paste")
			(net "GND")
		)
		(pad "144" smd rect
			(at -2.050034 63.324994 270)
			(size 0.519938 1.4986)
			(layers "F.Cu" "F.Mask" "F.Paste")
			(net "TP_CHH_CPU0_DIMM1_FRU_1")
		)
		(pad "145" smd rect
			(at 2.050034 -63.324994 270)
			(size 0.519938 1.4986)
			(layers "F.Cu" "F.Mask" "F.Paste")
			(net "P12V_S3_AUX_CPU0_NVDIMM")
		)
		(pad "146" smd rect
			(at 2.050034 -62.47511 270)
			(size 0.519938 1.4986)
			(layers "F.Cu" "F.Mask" "F.Paste")
			(net "P12V_S3_AUX_CPU0_NVDIMM")
		)
		(pad "147" smd rect
			(at 2.050034 -61.624972 270)
			(size 0.519938 1.4986)
			(layers "F.Cu" "F.Mask" "F.Paste")
			(net "PWRGD_CHH_CPU0_DIMM1")
		)
		(pad "148" smd rect
			(at 2.050034 -60.775088 270)
			(size 0.519938 1.4986)
			(layers "F.Cu" "F.Mask" "F.Paste")
			(net "PD_CHH_CPU0_DIMM1_SAA")
		)
		(pad "149" smd rect
			(at 2.050034 -59.92495 270)
			(size 0.519938 1.4986)
			(layers "F.Cu" "F.Mask" "F.Paste")
			(net "TP_CHH_CPU0_DIMM1_FRU_2")
		)
		(pad "150" smd rect
			(at 2.050034 -59.075066 270)
			(size 0.519938 1.4986)
			(layers "F.Cu" "F.Mask" "F.Paste")
			(net "TP_CHH_CPU0_DIMM1_FRU_3")
		)
		(pad "151" smd rect
			(at 2.050034 -58.224928 270)
			(size 0.519938 1.4986)
			(layers "F.Cu" "F.Mask" "F.Paste")
			(net "GND")
		)
		(pad "152" smd rect
			(at 2.050034 -57.375044 270)
			(size 0.519938 1.4986)
			(layers "F.Cu" "F.Mask" "F.Paste")
			(net "M_H_CPU0_SA_DQ<2>")
		)
		(pad "153" smd rect
			(at 2.050034 -56.524906 270)
			(size 0.519938 1.4986)
			(layers "F.Cu" "F.Mask" "F.Paste")
			(net "GND")
		)
		(pad "154" smd rect
			(at 2.050034 -55.675022 270)
			(size 0.519938 1.4986)
			(layers "F.Cu" "F.Mask" "F.Paste")
			(net "M_H_CPU0_SA_DQ<3>")
		)
		(pad "155" smd rect
			(at 2.050034 -54.824884 270)
			(size 0.519938 1.4986)
			(layers "F.Cu" "F.Mask" "F.Paste")
			(net "GND")
		)
		(pad "156" smd rect
			(at 2.050034 -53.975 270)
			(size 0.519938 1.4986)
			(layers "F.Cu" "F.Mask" "F.Paste")
			(net "M_H_CPU0_SA_DQS_DN<5>")
		)
		(pad "157" smd rect
			(at 2.050034 -53.125116 270)
			(size 0.519938 1.4986)
			(layers "F.Cu" "F.Mask" "F.Paste")
			(net "M_H_CPU0_SA_DQS_DP<5>")
		)
		(pad "158" smd rect
			(at 2.050034 -52.274978 270)
			(size 0.519938 1.4986)
			(layers "F.Cu" "F.Mask" "F.Paste")
			(net "GND")
		)
		(pad "159" smd rect
			(at 2.050034 -51.425094 270)
			(size 0.519938 1.4986)
			(layers "F.Cu" "F.Mask" "F.Paste")
			(net "M_H_CPU0_SA_DQ<6>")
		)
		(pad "160" smd rect
			(at 2.050034 -50.574956 270)
			(size 0.519938 1.4986)
			(layers "F.Cu" "F.Mask" "F.Paste")
			(net "GND")
		)
		(pad "161" smd rect
			(at 2.050034 -49.725072 270)
			(size 0.519938 1.4986)
			(layers "F.Cu" "F.Mask" "F.Paste")
			(net "M_H_CPU0_SA_DQ<7>")
		)
		(pad "162" smd rect
			(at 2.050034 -48.874934 270)
			(size 0.519938 1.4986)
			(layers "F.Cu" "F.Mask" "F.Paste")
			(net "GND")
		)
		(pad "163" smd rect
			(at 2.050034 -48.02505 270)
			(size 0.519938 1.4986)
			(layers "F.Cu" "F.Mask" "F.Paste")
			(net "M_H_CPU0_SA_DQ<10>")
		)
		(pad "164" smd rect
			(at 2.050034 -47.174912 270)
			(size 0.519938 1.4986)
			(layers "F.Cu" "F.Mask" "F.Paste")
			(net "GND")
		)
		(pad "165" smd rect
			(at 2.050034 -46.325028 270)
			(size 0.519938 1.4986)
			(layers "F.Cu" "F.Mask" "F.Paste")
			(net "M_H_CPU0_SA_DQ<11>")
		)
		(pad "166" smd rect
			(at 2.050034 -45.47489 270)
			(size 0.519938 1.4986)
			(layers "F.Cu" "F.Mask" "F.Paste")
			(net "GND")
		)
		(pad "167" smd rect
			(at 2.050034 -44.625006 270)
			(size 0.519938 1.4986)
			(layers "F.Cu" "F.Mask" "F.Paste")
			(net "M_H_CPU0_SA_DQS_DN<6>")
		)
		(pad "168" smd rect
			(at 2.050034 -43.775122 270)
			(size 0.519938 1.4986)
			(layers "F.Cu" "F.Mask" "F.Paste")
			(net "M_H_CPU0_SA_DQS_DP<6>")
		)
		(pad "169" smd rect
			(at 2.050034 -42.924984 270)
			(size 0.519938 1.4986)
			(layers "F.Cu" "F.Mask" "F.Paste")
			(net "GND")
		)
		(pad "170" smd rect
			(at 2.050034 -42.0751 270)
			(size 0.519938 1.4986)
			(layers "F.Cu" "F.Mask" "F.Paste")
			(net "M_H_CPU0_SA_DQ<14>")
		)
		(pad "171" smd rect
			(at 2.050034 -41.224962 270)
			(size 0.519938 1.4986)
			(layers "F.Cu" "F.Mask" "F.Paste")
			(net "GND")
		)
		(pad "172" smd rect
			(at 2.050034 -40.375078 270)
			(size 0.519938 1.4986)
			(layers "F.Cu" "F.Mask" "F.Paste")
			(net "M_H_CPU0_SA_DQ<15>")
		)
		(pad "173" smd rect
			(at 2.050034 -39.52494 270)
			(size 0.519938 1.4986)
			(layers "F.Cu" "F.Mask" "F.Paste")
			(net "GND")
		)
		(pad "174" smd rect
			(at 2.050034 -38.675056 270)
			(size 0.519938 1.4986)
			(layers "F.Cu" "F.Mask" "F.Paste")
			(net "M_H_CPU0_SA_DQ<18>")
		)
		(pad "175" smd rect
			(at 2.050034 -37.824918 270)
			(size 0.519938 1.4986)
			(layers "F.Cu" "F.Mask" "F.Paste")
			(net "GND")
		)
		(pad "176" smd rect
			(at 2.050034 -36.975034 270)
			(size 0.519938 1.4986)
			(layers "F.Cu" "F.Mask" "F.Paste")
			(net "M_H_CPU0_SA_DQ<19>")
		)
		(pad "177" smd rect
			(at 2.050034 -36.124896 270)
			(size 0.519938 1.4986)
			(layers "F.Cu" "F.Mask" "F.Paste")
			(net "GND")
		)
		(pad "178" smd rect
			(at 2.050034 -35.275012 270)
			(size 0.519938 1.4986)
			(layers "F.Cu" "F.Mask" "F.Paste")
			(net "M_H_CPU0_SA_DQS_DN<7>")
		)
		(pad "179" smd rect
			(at 2.050034 -34.425128 270)
			(size 0.519938 1.4986)
			(layers "F.Cu" "F.Mask" "F.Paste")
			(net "M_H_CPU0_SA_DQS_DP<7>")
		)
		(pad "180" smd rect
			(at 2.050034 -33.57499 270)
			(size 0.519938 1.4986)
			(layers "F.Cu" "F.Mask" "F.Paste")
			(net "GND")
		)
		(pad "181" smd rect
			(at 2.050034 -32.725106 270)
			(size 0.519938 1.4986)
			(layers "F.Cu" "F.Mask" "F.Paste")
			(net "M_H_CPU0_SA_DQ<22>")
		)
		(pad "182" smd rect
			(at 2.050034 -31.874968 270)
			(size 0.519938 1.4986)
			(layers "F.Cu" "F.Mask" "F.Paste")
			(net "GND")
		)
		(pad "183" smd rect
			(at 2.050034 -31.025084 270)
			(size 0.519938 1.4986)
			(layers "F.Cu" "F.Mask" "F.Paste")
			(net "M_H_CPU0_SA_DQ<23>")
		)
		(pad "184" smd rect
			(at 2.050034 -30.174946 270)
			(size 0.519938 1.4986)
			(layers "F.Cu" "F.Mask" "F.Paste")
			(net "GND")
		)
		(pad "185" smd rect
			(at 2.050034 -29.325062 270)
			(size 0.519938 1.4986)
			(layers "F.Cu" "F.Mask" "F.Paste")
			(net "M_H_CPU0_SA_DQ<26>")
		)
		(pad "186" smd rect
			(at 2.050034 -28.474924 270)
			(size 0.519938 1.4986)
			(layers "F.Cu" "F.Mask" "F.Paste")
			(net "GND")
		)
		(pad "187" smd rect
			(at 2.050034 -27.62504 270)
			(size 0.519938 1.4986)
			(layers "F.Cu" "F.Mask" "F.Paste")
			(net "M_H_CPU0_SA_DQ<27>")
		)
		(pad "188" smd rect
			(at 2.050034 -26.774902 270)
			(size 0.519938 1.4986)
			(layers "F.Cu" "F.Mask" "F.Paste")
			(net "GND")
		)
		(pad "189" smd rect
			(at 2.050034 -25.925018 270)
			(size 0.519938 1.4986)
			(layers "F.Cu" "F.Mask" "F.Paste")
			(net "M_H_CPU0_SA_DQS_DN<8>")
		)
		(pad "190" smd rect
			(at 2.050034 -25.07488 270)
			(size 0.519938 1.4986)
			(layers "F.Cu" "F.Mask" "F.Paste")
			(net "M_H_CPU0_SA_DQS_DP<8>")
		)
		(pad "191" smd rect
			(at 2.050034 -24.224996 270)
			(size 0.519938 1.4986)
			(layers "F.Cu" "F.Mask" "F.Paste")
			(net "GND")
		)
		(pad "192" smd rect
			(at 2.050034 -23.375112 270)
			(size 0.519938 1.4986)
			(layers "F.Cu" "F.Mask" "F.Paste")
			(net "M_H_CPU0_SA_DQ<30>")
		)
		(pad "193" smd rect
			(at 2.050034 -22.524974 270)
			(size 0.519938 1.4986)
			(layers "F.Cu" "F.Mask" "F.Paste")
			(net "GND")
		)
		(pad "194" smd rect
			(at 2.050034 -21.67509 270)
			(size 0.519938 1.4986)
			(layers "F.Cu" "F.Mask" "F.Paste")
			(net "M_H_CPU0_SA_DQ<31>")
		)
		(pad "195" smd rect
			(at 2.050034 -20.824952 270)
			(size 0.519938 1.4986)
			(layers "F.Cu" "F.Mask" "F.Paste")
			(net "GND")
		)
		(pad "196" smd rect
			(at 2.050034 -19.975068 270)
			(size 0.519938 1.4986)
			(layers "F.Cu" "F.Mask" "F.Paste")
			(net "M_H_CPU0_SA_CB<2>")
		)
		(pad "197" smd rect
			(at 2.050034 -19.12493 270)
			(size 0.519938 1.4986)
			(layers "F.Cu" "F.Mask" "F.Paste")
			(net "GND")
		)
		(pad "198" smd rect
			(at 2.050034 -18.275046 270)
			(size 0.519938 1.4986)
			(layers "F.Cu" "F.Mask" "F.Paste")
			(net "M_H_CPU0_SA_CB<3>")
		)
		(pad "199" smd rect
			(at 2.050034 -17.424908 270)
			(size 0.519938 1.4986)
			(layers "F.Cu" "F.Mask" "F.Paste")
			(net "GND")
		)
		(pad "200" smd rect
			(at 2.050034 -16.575024 270)
			(size 0.519938 1.4986)
			(layers "F.Cu" "F.Mask" "F.Paste")
			(net "M_H_CPU0_SA_DQS_DN<9>")
		)
		(pad "201" smd rect
			(at 2.050034 -15.724886 270)
			(size 0.519938 1.4986)
			(layers "F.Cu" "F.Mask" "F.Paste")
			(net "M_H_CPU0_SA_DQS_DP<9>")
		)
		(pad "202" smd rect
			(at 2.050034 -14.875002 270)
			(size 0.519938 1.4986)
			(layers "F.Cu" "F.Mask" "F.Paste")
			(net "GND")
		)
		(pad "203" smd rect
			(at 2.050034 -14.025118 270)
			(size 0.519938 1.4986)
			(layers "F.Cu" "F.Mask" "F.Paste")
			(net "M_H_CPU0_SA_CB<6>")
		)
		(pad "204" smd rect
			(at 2.050034 -13.17498 270)
			(size 0.519938 1.4986)
			(layers "F.Cu" "F.Mask" "F.Paste")
			(net "GND")
		)
		(pad "205" smd rect
			(at 2.050034 -12.325096 270)
			(size 0.519938 1.4986)
			(layers "F.Cu" "F.Mask" "F.Paste")
			(net "M_H_CPU0_SA_CB<7>")
		)
		(pad "206" smd rect
			(at 2.050034 -11.474958 270)
			(size 0.519938 1.4986)
			(layers "F.Cu" "F.Mask" "F.Paste")
			(net "GND")
		)
		(pad "207" smd rect
			(at 2.050034 -10.625074 270)
			(size 0.519938 1.4986)
			(layers "F.Cu" "F.Mask" "F.Paste")
			(net "RST_M_GH_CPU0_FPGA_N")
		)
		(pad "208" smd rect
			(at 2.050034 -9.774936 270)
			(size 0.519938 1.4986)
			(layers "F.Cu" "F.Mask" "F.Paste")
			(net "GND")
		)
		(pad "209" smd rect
			(at 2.050034 -8.925052 270)
			(size 0.519938 1.4986)
			(layers "F.Cu" "F.Mask" "F.Paste")
			(net "M_H_CPU0_SA_CS_N<1>")
		)
		(pad "210" smd rect
			(at 2.050034 -8.074914 270)
			(size 0.519938 1.4986)
			(layers "F.Cu" "F.Mask" "F.Paste")
			(net "GND")
		)
		(pad "211" smd rect
			(at 2.050034 -7.22503 270)
			(size 0.519938 1.4986)
			(layers "F.Cu" "F.Mask" "F.Paste")
			(net "M_H_CPU0_SA_CA<1>")
		)
		(pad "212" smd rect
			(at 2.050034 -6.374892 270)
			(size 0.519938 1.4986)
			(layers "F.Cu" "F.Mask" "F.Paste")
			(net "GND")
		)
		(pad "213" smd rect
			(at 2.050034 -5.525008 270)
			(size 0.519938 1.4986)
			(layers "F.Cu" "F.Mask" "F.Paste")
			(net "M_H_CPU0_SA_CA<3>")
		)
		(pad "214" smd rect
			(at 2.050034 -4.675124 270)
			(size 0.519938 1.4986)
			(layers "F.Cu" "F.Mask" "F.Paste")
			(net "GND")
		)
		(pad "215" smd rect
			(at 2.050034 -3.824986 270)
			(size 0.519938 1.4986)
			(layers "F.Cu" "F.Mask" "F.Paste")
			(net "M_H_CPU0_SA_CA<5>")
		)
		(pad "216" smd rect
			(at 2.050034 -2.975102 270)
			(size 0.519938 1.4986)
			(layers "F.Cu" "F.Mask" "F.Paste")
			(net "GND")
		)
		(pad "217" smd rect
			(at 2.050034 -2.124964 270)
			(size 0.519938 1.4986)
			(layers "F.Cu" "F.Mask" "F.Paste")
			(net "M_H_CPU0_CLK_DP<0>")
		)
		(pad "218" smd rect
			(at 2.050034 -1.27508 270)
			(size 0.519938 1.4986)
			(layers "F.Cu" "F.Mask" "F.Paste")
			(net "M_H_CPU0_CLK_DN<0>")
		)
		(pad "219" smd rect
			(at 2.050034 -0.424942 270)
			(size 0.519938 1.4986)
			(layers "F.Cu" "F.Mask" "F.Paste")
			(net "GND")
		)
		(pad "220" smd rect
			(at 2.050034 5.525008 270)
			(size 0.519938 1.4986)
			(layers "F.Cu" "F.Mask" "F.Paste")
			(net "TP_CHH_CPU0_DIMM1_FRU_4")
		)
		(pad "221" smd rect
			(at 2.050034 6.374892 270)
			(size 0.519938 1.4986)
			(layers "F.Cu" "F.Mask" "F.Paste")
			(net "M_H_CPU0_SB_CA<1>")
		)
		(pad "222" smd rect
			(at 2.050034 7.22503 270)
			(size 0.519938 1.4986)
			(layers "F.Cu" "F.Mask" "F.Paste")
			(net "GND")
		)
		(pad "223" smd rect
			(at 2.050034 8.074914 270)
			(size 0.519938 1.4986)
			(layers "F.Cu" "F.Mask" "F.Paste")
			(net "M_H_CPU0_SB_CA<3>")
		)
		(pad "224" smd rect
			(at 2.050034 8.925052 270)
			(size 0.519938 1.4986)
			(layers "F.Cu" "F.Mask" "F.Paste")
			(net "GND")
		)
	)
)
